FILE_TYPE = CONNECTIVITY;
{Allegro Design Entry HDL 17.2-2016 S081 (4005846) 1/11/2022}
"PAGE_NUMBER" = 89;
0"NC";
1"P3V3_AUX\g";
2"P3V3_AUX\g";
3"P12V_S3_AUX_CPU0_NVDIMM\g";
4"P12V_S3_AUX_CPU0_NVDIMM\g";
5"GND\g";
6"GND\g";
7"GND\g";
8"GND\g";
9"GND\g";
10"M_D_CPU0_SB_CB<7:0>";
11"M_D_CPU0_SA_CB<7:0>";
12"M_D_CPU0_SA_CA<6:0>";
13"M_D_CPU0_SA_DQ<31:0>";
14"M_D_CPU0_SB_DQ<31:0>";
15"M_D_CPU0_SB_CA<6:0>";
16"M_D_CPU0_SA_DQS_DP<9:0>";
17"M_D_CPU0_SB_DQS_DP<9:0>";
18"M_D_CPU0_SB_DQS_DN<9:0>";
19"M_D_CPU0_SA_DQS_DN<9:0>";
20"I3C_SPD_DDRABCD_CPU0_LVC1_SDA";
21"PD_CHD_CPU0_DIMM2_SAA";
22"RST_M_CD_CPU0_FPGA_N";
23"M_D_CPU0_ALERT_N";
24"I3C_SPD_DDRABCD_CPU0_LVC1_SCL_R8";
25"I3C_SPD_DDRABCD_CPU0_LVC1_SCL";
26"PWRGD_CHD_CPU0_DIMM2";
27"TP_CHD_CPU0_DIMM2_FRU_6";
28"M_D_CPU0_SB_CB<0>";
29"M_D_CPU0_SB_CB<2>";
30"M_D_CPU0_SA_CB<0>";
31"M_D_CPU0_SA_DQS_DN<9>";
32"M_D_CPU0_SA_DQS_DN<8>";
33"M_D_CPU0_SA_DQS_DN<6>";
34"M_D_CPU0_SA_DQS_DN<7>";
35"M_D_CPU0_SA_DQS_DN<5>";
36"M_D_CPU0_SA_DQS_DN<4>";
37"M_D_CPU0_SA_DQS_DN<3>";
38"M_D_CPU0_SA_DQS_DN<1>";
39"M_D_CPU0_SA_DQS_DN<2>";
40"M_D_CPU0_SA_DQS_DN<0>";
41"M_D_CPU0_SB_DQS_DN<9>";
42"M_D_CPU0_SB_DQS_DN<8>";
43"M_D_CPU0_SB_DQS_DN<7>";
44"M_D_CPU0_SB_DQS_DN<6>";
45"M_D_CPU0_SB_DQS_DN<5>";
46"M_D_CPU0_SB_DQS_DN<4>";
47"M_D_CPU0_SB_DQS_DN<3>";
48"M_D_CPU0_SB_DQS_DN<2>";
49"M_D_CPU0_SB_DQS_DN<0>";
50"M_D_CPU0_SB_DQS_DN<1>";
51"M_D_CPU0_SA_DQS_DP<9>";
52"M_D_CPU0_SA_DQS_DP<8>";
53"M_D_CPU0_SB_DQS_DP<0>";
54"M_D_CPU0_SB_DQS_DP<1>";
55"M_D_CPU0_SB_DQS_DP<2>";
56"M_D_CPU0_SB_DQS_DP<3>";
57"M_D_CPU0_SB_DQS_DP<4>";
58"M_D_CPU0_SB_DQS_DP<5>";
59"M_D_CPU0_SB_DQS_DP<6>";
60"M_D_CPU0_SB_DQS_DP<7>";
61"M_D_CPU0_SB_DQS_DP<8>";
62"M_D_CPU0_SB_DQS_DP<9>";
63"M_D_CPU0_SA_DQS_DP<0>";
64"M_D_CPU0_SA_DQS_DP<1>";
65"M_D_CPU0_SA_DQS_DP<2>";
66"M_D_CPU0_SA_DQS_DP<3>";
67"M_D_CPU0_SA_DQS_DP<4>";
68"M_D_CPU0_SA_DQS_DP<5>";
69"M_D_CPU0_SA_DQS_DP<6>";
70"M_D_CPU0_SA_DQS_DP<7>";
71"TP_CHD_CPU0_DIMM2_FRU_5";
72"PD_CHD_CPU0_DIMM2_SAA";
73"M_D_CPU0_SA_DQ<31>";
74"M_D_CPU0_SA_CB<7>";
75"M_D_CPU0_SA_CB<4>";
76"M_D_CPU0_SA_CB<1>";
77"M_D_CPU0_SB_CB<7>";
78"M_D_CPU0_SA_CA<0>";
79"M_D_CPU0_SB_CA<0>";
80"M_D_CPU0_SA_CA<1>";
81"M_D_CPU0_SB_CA<1>";
82"M_D_CPU0_SA_CA<2>";
83"M_D_CPU0_SB_CA<2>";
84"M_D_CPU0_SA_CA<3>";
85"M_D_CPU0_SB_CA<3>";
86"M_D_CPU0_SB_CA<4>";
87"M_D_CPU0_SB_CA<5>";
88"M_D_CPU0_SB_CA<6>";
89"M_D_CPU0_SA_CB<6>";
90"M_D_CPU0_SA_CB<3>";
91"M_D_CPU0_SA_CB<2>";
92"M_D_CPU0_SB_CB<6>";
93"M_D_CPU0_SB_CB<5>";
94"M_D_CPU0_SB_CB<4>";
95"M_D_CPU0_SB_CB<1>";
96"M_D_CPU0_CLK_DN<1>";
97"M_D_CPU0_CLK_DP<1>";
98"M_D_CPU0_SA_CS_N<2>";
99"M_D_CPU0_SB_CS_N<2>";
100"M_D_CPU0_SA_CS_N<3>";
101"M_D_CPU0_SB_CS_N<3>";
102"M_D_CPU0_SA_DQ<30>";
103"M_D_CPU0_SA_DQ<29>";
104"M_D_CPU0_SA_DQ<28>";
105"M_D_CPU0_SA_DQ<27>";
106"M_D_CPU0_SA_DQ<26>";
107"M_D_CPU0_SA_DQ<25>";
108"M_D_CPU0_SA_DQ<24>";
109"M_D_CPU0_SA_DQ<23>";
110"M_D_CPU0_SA_DQ<22>";
111"M_D_CPU0_SA_DQ<21>";
112"M_D_CPU0_SA_DQ<20>";
113"M_D_CPU0_SA_DQ<19>";
114"M_D_CPU0_SA_DQ<18>";
115"M_D_CPU0_SA_DQ<17>";
116"M_D_CPU0_SA_DQ<13>";
117"M_D_CPU0_SA_DQ<12>";
118"M_D_CPU0_SA_DQ<11>";
119"M_D_CPU0_SA_DQ<10>";
120"M_D_CPU0_SA_DQ<9>";
121"M_D_CPU0_SA_DQ<8>";
122"M_D_CPU0_SA_DQ<7>";
123"M_D_CPU0_SA_DQ<6>";
124"M_D_CPU0_SA_DQ<5>";
125"M_D_CPU0_SA_DQ<4>";
126"M_D_CPU0_SA_DQ<3>";
127"M_D_CPU0_SA_DQ<2>";
128"M_D_CPU0_SA_DQ<1>";
129"M_D_CPU0_SA_DQ<0>";
130"M_D_CPU0_SB_DQ<31>";
131"M_D_CPU0_SB_DQ<30>";
132"M_D_CPU0_SB_DQ<29>";
133"M_D_CPU0_SB_DQ<28>";
134"M_D_CPU0_SB_DQ<27>";
135"M_D_CPU0_SB_DQ<26>";
136"M_D_CPU0_SB_DQ<25>";
137"M_D_CPU0_SB_DQ<24>";
138"M_D_CPU0_SB_DQ<23>";
139"M_D_CPU0_SB_DQ<22>";
140"M_D_CPU0_SB_DQ<21>";
141"M_D_CPU0_SB_DQ<20>";
142"M_D_CPU0_SB_DQ<19>";
143"M_D_CPU0_SB_DQ<18>";
144"M_D_CPU0_SB_DQ<17>";
145"M_D_CPU0_SB_DQ<16>";
146"M_D_CPU0_SB_DQ<15>";
147"M_D_CPU0_SB_DQ<14>";
148"M_D_CPU0_SB_DQ<13>";
149"M_D_CPU0_SB_DQ<11>";
150"M_D_CPU0_SB_DQ<10>";
151"M_D_CPU0_SB_DQ<9>";
152"M_D_CPU0_SB_DQ<8>";
153"M_D_CPU0_SB_DQ<7>";
154"M_D_CPU0_SB_DQ<6>";
155"M_D_CPU0_SB_DQ<5>";
156"M_D_CPU0_SB_DQ<4>";
157"M_D_CPU0_SB_DQ<3>";
158"M_D_CPU0_SB_DQ<2>";
159"M_D_CPU0_SB_DQ<1>";
160"M_D_CPU0_SB_DQ<0>";
161"M_D_CPU0_SA_RSP<1>";
162"M_D_CPU0_SB_RSP<1>";
163"M_D_CPU0_SA_PAR";
164"M_D_CPU0_SB_PAR";
165"TP_CHD_CPU0_DIMM2_FRU_4";
166"TP_CHD_CPU0_DIMM2_FRU_3";
167"TP_CHD_CPU0_DIMM2_FRU_2";
168"TP_CHD_CPU0_DIMM2_FRU_1";
169"TP_CHD_CPU0_DIMM2_FRU_0";
170"M_D_CPU0_SB_DQ<12>";
171"M_D_CPU0_SA_DQ<16>";
172"M_D_CPU0_SA_DQ<14>";
173"M_D_CPU0_SA_DQ<15>";
174"M_D_CPU0_SA_CA<4>";
175"M_D_CPU0_SA_CA<5>";
176"M_D_CPU0_SA_CA<6>";
177"M_D_CPU0_SA_CB<5>";
178"M_D_CPU0_SB_CB<3>";
%"UNIVERSAL_GND"
"1","(-2125,-175)","0","logical_power","I1";
;
CDS_LIB"logical_power"
HDL_POWER"GND";
"A"5;
%"TAP"
"1","(-700,3500)","0","standard","I100";
;
CDS_LIB"standard"
BODY_TYPE"PLUMBING"
HDL_TAP"TRUE";
"B \NAC \NWC"13;
"S \NAC"
BN"17"115;
%"TAP"
"1","(-700,3550)","0","standard","I101";
;
CDS_LIB"standard"
BODY_TYPE"PLUMBING"
HDL_TAP"TRUE";
"B \NAC \NWC"13;
"S \NAC"
BN"18"114;
%"TAP"
"1","(-700,3600)","0","standard","I102";
;
CDS_LIB"standard"
BODY_TYPE"PLUMBING"
HDL_TAP"TRUE";
"B \NAC \NWC"13;
"S \NAC"
BN"19"113;
%"TAP"
"1","(-700,3650)","0","standard","I103";
;
CDS_LIB"standard"
BODY_TYPE"PLUMBING"
HDL_TAP"TRUE";
"B \NAC \NWC"13;
"S \NAC"
BN"20"112;
%"TAP"
"1","(-700,3700)","0","standard","I104";
;
CDS_LIB"standard"
BODY_TYPE"PLUMBING"
HDL_TAP"TRUE";
"B \NAC \NWC"13;
"S \NAC"
BN"21"111;
%"TAP"
"1","(-700,3750)","0","standard","I105";
;
CDS_LIB"standard"
BODY_TYPE"PLUMBING"
HDL_TAP"TRUE";
"B \NAC \NWC"13;
"S \NAC"
BN"22"110;
%"TAP"
"1","(-700,3800)","0","standard","I106";
;
CDS_LIB"standard"
BODY_TYPE"PLUMBING"
HDL_TAP"TRUE";
"B \NAC \NWC"13;
"S \NAC"
BN"23"109;
%"TAP"
"1","(-700,3900)","0","standard","I107";
;
CDS_LIB"standard"
BODY_TYPE"PLUMBING"
HDL_TAP"TRUE";
"B \NAC \NWC"13;
"S \NAC"
BN"25"107;
%"TAP"
"1","(-700,3850)","0","standard","I108";
;
CDS_LIB"standard"
BODY_TYPE"PLUMBING"
HDL_TAP"TRUE";
"B \NAC \NWC"13;
"S \NAC"
BN"24"108;
%"TAP"
"1","(-700,3950)","0","standard","I109";
;
CDS_LIB"standard"
BODY_TYPE"PLUMBING"
HDL_TAP"TRUE";
"B \NAC \NWC"13;
"S \NAC"
BN"26"106;
%"VCC_CORE"
"1","(-3175,2075)","0","logical_power","I11";
;
HDL_POWER"P3V3_AUX"
CDS_LIB"logical_power";
"A"1;
%"TAP"
"1","(-700,4000)","0","standard","I110";
;
CDS_LIB"standard"
BODY_TYPE"PLUMBING"
HDL_TAP"TRUE";
"B \NAC \NWC"13;
"S \NAC"
BN"27"105;
%"TAP"
"1","(-700,4050)","0","standard","I111";
;
CDS_LIB"standard"
BODY_TYPE"PLUMBING"
HDL_TAP"TRUE";
"B \NAC \NWC"13;
"S \NAC"
BN"28"104;
%"TAP"
"1","(-2350,4100)","2","standard","I113";
;
CDS_LIB"standard"
BODY_TYPE"PLUMBING"
HDL_TAP"TRUE";
"B \NAC \NWC"12;
"S \NAC"
BN"4"174;
%"TAP"
"1","(-2350,4150)","2","standard","I114";
;
CDS_LIB"standard"
BODY_TYPE"PLUMBING"
HDL_TAP"TRUE";
"B \NAC \NWC"12;
"S \NAC"
BN"5"175;
%"TAP"
"1","(-2350,4200)","2","standard","I115";
;
CDS_LIB"standard"
BODY_TYPE"PLUMBING"
HDL_TAP"TRUE";
"B \NAC \NWC"12;
"S \NAC"
BN"6"176;
%"TAP"
"1","(-700,4100)","0","standard","I116";
;
CDS_LIB"standard"
BODY_TYPE"PLUMBING"
HDL_TAP"TRUE";
"B \NAC \NWC"13;
"S \NAC"
BN"29"103;
%"TAP"
"1","(-700,4150)","0","standard","I117";
;
CDS_LIB"standard"
BODY_TYPE"PLUMBING"
HDL_TAP"TRUE";
"B \NAC \NWC"13;
"S \NAC"
BN"30"102;
%"TAP"
"1","(-700,4200)","0","standard","I118";
;
CDS_LIB"standard"
BODY_TYPE"PLUMBING"
HDL_TAP"TRUE";
"B \NAC \NWC"13;
"S \NAC"
BN"31"73;
%"UNIVERSAL_GND"
"1","(1025,-50)","0","logical_power","I119";
;
CDS_LIB"logical_power"
HDL_POWER"GND";
"A"6;
%"TAP"
"1","(-2350,2000)","2","standard","I12";
;
CDS_LIB"standard"
BODY_TYPE"PLUMBING"
HDL_TAP"TRUE";
"B \NAC \NWC"10;
"S \NAC"
BN"0"28;
%"UNIVERSAL_GND"
"1","(2650,-50)","0","logical_power","I120";
;
CDS_LIB"logical_power"
HDL_POWER"GND";
"A"7;
%"Q_CAP"
"1","(1025,325)","0","pure_quanta","I121";
;
PART_NUMBER"CH5221MEB00"
PACK_TYPE"C0402"
TOLERANCE"20%"
VALUE"2.2UF"
MATERIAL"X6S"
VOLTAGE"6.3V"
$LOCATION"C23"
CDS_LIB"pure_quanta"
CDS_LOCATION"C23"
$SEC"1"
CDS_SEC"1";
"B"
$PN"2"6;
"A"
$PN"1"2;
%"VCC_CORE"
"1","(1025,650)","0","logical_power","I122";
;
HDL_POWER"P3V3_AUX"
CDS_LIB"logical_power";
"A"2;
%"Q_CAP"
"1","(2025,325)","0","pure_quanta","I125";
;
PART_NUMBER"CH6103KEA00"
MATERIAL"X6S"
VALUE"10UF"
TOLERANCE"10%"
PACK_TYPE"C0805"
VOLTAGE"16V"
$LOCATION"C24"
CDS_LIB"pure_quanta"
CDS_LOCATION"C24"
$SEC"1"
CDS_SEC"1";
"B"
$PN"2"7;
"A"
$PN"1"3;
%"VCC_CORE"
"1","(2025,650)","0","logical_power","I126";
;
HDL_POWER"P12V_S3_AUX_CPU0_NVDIMM"
CDS_LIB"logical_power";
"A"3;
%"Q_CAP"
"1","(2650,325)","0","pure_quanta","I127";
;
PART_NUMBER"CH6103KEA00"
TOLERANCE"10%"
VALUE"10UF"
PACK_TYPE"C0805"
MATERIAL"X6S"
VOLTAGE"16V"
$LOCATION"C25"
CDS_LIB"pure_quanta"
CDS_LOCATION"C25"
$SEC"1"
CDS_SEC"1";
"B"
$PN"2"7;
"A"
$PN"1"3;
%"UNIVERSAL_GND"
"1","(3725,500)","0","logical_power","I128";
;
CDS_LIB"logical_power"
HDL_POWER"GND";
"A"8;
%"TAP"
"1","(2050,2250)","0","standard","I129";
;
CDS_LIB"standard"
BODY_TYPE"PLUMBING"
HDL_TAP"TRUE";
"B \NAC \NWC"17;
"S \NAC"
BN"0"53;
%"TAP"
"1","(2050,2350)","0","standard","I130";
;
CDS_LIB"standard"
BODY_TYPE"PLUMBING"
HDL_TAP"TRUE";
"B \NAC \NWC"17;
"S \NAC"
BN"1"54;
%"TAP"
"1","(2050,2450)","0","standard","I131";
;
CDS_LIB"standard"
BODY_TYPE"PLUMBING"
HDL_TAP"TRUE";
"B \NAC \NWC"17;
"S \NAC"
BN"2"55;
%"TAP"
"1","(2050,2550)","0","standard","I132";
;
CDS_LIB"standard"
BODY_TYPE"PLUMBING"
HDL_TAP"TRUE";
"B \NAC \NWC"17;
"S \NAC"
BN"3"56;
%"TAP"
"1","(2225,2300)","0","standard","I133";
;
CDS_LIB"standard"
BODY_TYPE"PLUMBING"
HDL_TAP"TRUE";
"B \NAC \NWC"18;
"S \NAC"
BN"1"50;
%"TAP"
"1","(2225,2200)","0","standard","I134";
;
CDS_LIB"standard"
BODY_TYPE"PLUMBING"
HDL_TAP"TRUE";
"B \NAC \NWC"18;
"S \NAC"
BN"0"49;
%"TAP"
"1","(2225,2400)","0","standard","I135";
;
CDS_LIB"standard"
BODY_TYPE"PLUMBING"
HDL_TAP"TRUE";
"B \NAC \NWC"18;
"S \NAC"
BN"2"48;
%"TAP"
"1","(2225,2500)","0","standard","I136";
;
CDS_LIB"standard"
BODY_TYPE"PLUMBING"
HDL_TAP"TRUE";
"B \NAC \NWC"18;
"S \NAC"
BN"3"47;
%"TAP"
"1","(2050,2650)","0","standard","I137";
;
CDS_LIB"standard"
BODY_TYPE"PLUMBING"
HDL_TAP"TRUE";
"B \NAC \NWC"17;
"S \NAC"
BN"4"57;
%"TAP"
"1","(2050,2750)","0","standard","I138";
;
CDS_LIB"standard"
BODY_TYPE"PLUMBING"
HDL_TAP"TRUE";
"B \NAC \NWC"17;
"S \NAC"
BN"5"58;
%"TAP"
"1","(2050,2850)","0","standard","I139";
;
CDS_LIB"standard"
BODY_TYPE"PLUMBING"
HDL_TAP"TRUE";
"B \NAC \NWC"17;
"S \NAC"
BN"6"59;
%"TAP"
"1","(2050,2950)","0","standard","I140";
;
CDS_LIB"standard"
BODY_TYPE"PLUMBING"
HDL_TAP"TRUE";
"B \NAC \NWC"17;
"S \NAC"
BN"7"60;
%"TAP"
"1","(2050,3050)","0","standard","I141";
;
CDS_LIB"standard"
BODY_TYPE"PLUMBING"
HDL_TAP"TRUE";
"B \NAC \NWC"17;
"S \NAC"
BN"8"61;
%"TAP"
"1","(2225,2600)","0","standard","I142";
;
CDS_LIB"standard"
BODY_TYPE"PLUMBING"
HDL_TAP"TRUE";
"B \NAC \NWC"18;
"S \NAC"
BN"4"46;
%"TAP"
"1","(2225,2800)","0","standard","I143";
;
CDS_LIB"standard"
BODY_TYPE"PLUMBING"
HDL_TAP"TRUE";
"B \NAC \NWC"18;
"S \NAC"
BN"6"44;
%"TAP"
"1","(2225,2700)","0","standard","I144";
;
CDS_LIB"standard"
BODY_TYPE"PLUMBING"
HDL_TAP"TRUE";
"B \NAC \NWC"18;
"S \NAC"
BN"5"45;
%"TAP"
"1","(2225,2900)","0","standard","I145";
;
CDS_LIB"standard"
BODY_TYPE"PLUMBING"
HDL_TAP"TRUE";
"B \NAC \NWC"18;
"S \NAC"
BN"7"43;
%"TAP"
"1","(2225,3000)","0","standard","I146";
;
CDS_LIB"standard"
BODY_TYPE"PLUMBING"
HDL_TAP"TRUE";
"B \NAC \NWC"18;
"S \NAC"
BN"8"42;
%"TAP"
"1","(2050,3150)","0","standard","I147";
;
CDS_LIB"standard"
BODY_TYPE"PLUMBING"
HDL_TAP"TRUE";
"B \NAC \NWC"17;
"S \NAC"
BN"9"62;
%"TAP"
"1","(2050,3300)","0","standard","I148";
;
CDS_LIB"standard"
BODY_TYPE"PLUMBING"
HDL_TAP"TRUE";
"B \NAC \NWC"16;
"S \NAC"
BN"0"63;
%"TAP"
"1","(2050,3400)","0","standard","I149";
;
CDS_LIB"standard"
BODY_TYPE"PLUMBING"
HDL_TAP"TRUE";
"B \NAC \NWC"16;
"S \NAC"
BN"1"64;
%"TAP"
"1","(2050,3500)","0","standard","I150";
;
CDS_LIB"standard"
BODY_TYPE"PLUMBING"
HDL_TAP"TRUE";
"B \NAC \NWC"16;
"S \NAC"
BN"2"65;
%"TAP"
"1","(2225,3100)","0","standard","I151";
;
CDS_LIB"standard"
BODY_TYPE"PLUMBING"
HDL_TAP"TRUE";
"B \NAC \NWC"18;
"S \NAC"
BN"9"41;
%"TAP"
"1","(2225,3250)","0","standard","I152";
;
CDS_LIB"standard"
BODY_TYPE"PLUMBING"
HDL_TAP"TRUE";
"B \NAC \NWC"19;
"S \NAC"
BN"0"40;
%"TAP"
"1","(2225,3450)","0","standard","I153";
;
CDS_LIB"standard"
BODY_TYPE"PLUMBING"
HDL_TAP"TRUE";
"B \NAC \NWC"19;
"S \NAC"
BN"2"39;
%"TAP"
"1","(2225,3350)","0","standard","I154";
;
CDS_LIB"standard"
BODY_TYPE"PLUMBING"
HDL_TAP"TRUE";
"B \NAC \NWC"19;
"S \NAC"
BN"1"38;
%"TAP"
"1","(2225,3550)","0","standard","I155";
;
CDS_LIB"standard"
BODY_TYPE"PLUMBING"
HDL_TAP"TRUE";
"B \NAC \NWC"19;
"S \NAC"
BN"3"37;
%"TAP"
"1","(2050,3600)","0","standard","I156";
;
CDS_LIB"standard"
BODY_TYPE"PLUMBING"
HDL_TAP"TRUE";
"B \NAC \NWC"16;
"S \NAC"
BN"3"66;
%"TAP"
"1","(2050,3700)","0","standard","I157";
;
CDS_LIB"standard"
BODY_TYPE"PLUMBING"
HDL_TAP"TRUE";
"B \NAC \NWC"16;
"S \NAC"
BN"4"67;
%"TAP"
"1","(2050,3800)","0","standard","I158";
;
CDS_LIB"standard"
BODY_TYPE"PLUMBING"
HDL_TAP"TRUE";
"B \NAC \NWC"16;
"S \NAC"
BN"5"68;
%"TAP"
"1","(2050,3900)","0","standard","I159";
;
CDS_LIB"standard"
BODY_TYPE"PLUMBING"
HDL_TAP"TRUE";
"B \NAC \NWC"16;
"S \NAC"
BN"6"69;
%"TAP"
"1","(2050,4000)","0","standard","I160";
;
CDS_LIB"standard"
BODY_TYPE"PLUMBING"
HDL_TAP"TRUE";
"B \NAC \NWC"16;
"S \NAC"
BN"7"70;
%"TAP"
"1","(2225,3650)","0","standard","I161";
;
CDS_LIB"standard"
BODY_TYPE"PLUMBING"
HDL_TAP"TRUE";
"B \NAC \NWC"19;
"S \NAC"
BN"4"36;
%"TAP"
"1","(2225,3750)","0","standard","I162";
;
CDS_LIB"standard"
BODY_TYPE"PLUMBING"
HDL_TAP"TRUE";
"B \NAC \NWC"19;
"S \NAC"
BN"5"35;
%"TAP"
"1","(2225,3950)","0","standard","I163";
;
CDS_LIB"standard"
BODY_TYPE"PLUMBING"
HDL_TAP"TRUE";
"B \NAC \NWC"19;
"S \NAC"
BN"7"34;
%"TAP"
"1","(2225,3850)","0","standard","I164";
;
CDS_LIB"standard"
BODY_TYPE"PLUMBING"
HDL_TAP"TRUE";
"B \NAC \NWC"19;
"S \NAC"
BN"6"33;
%"TAP"
"1","(2225,4050)","0","standard","I165";
;
CDS_LIB"standard"
BODY_TYPE"PLUMBING"
HDL_TAP"TRUE";
"B \NAC \NWC"19;
"S \NAC"
BN"8"32;
%"TAP"
"1","(2050,4200)","0","standard","I169";
;
CDS_LIB"standard"
BODY_TYPE"PLUMBING"
HDL_TAP"TRUE";
"B \NAC \NWC"16;
"S \NAC"
BN"9"51;
%"TAP"
"1","(2050,4100)","0","standard","I170";
;
CDS_LIB"standard"
BODY_TYPE"PLUMBING"
HDL_TAP"TRUE";
"B \NAC \NWC"16;
"S \NAC"
BN"8"52;
%"TAP"
"1","(2225,4150)","0","standard","I171";
;
CDS_LIB"standard"
BODY_TYPE"PLUMBING"
HDL_TAP"TRUE";
"B \NAC \NWC"19;
"S \NAC"
BN"9"31;
%"VCC_CORE"
"1","(3725,4750)","0","logical_power","I174";
;
HDL_POWER"P12V_S3_AUX_CPU0_NVDIMM"
CDS_LIB"logical_power";
"A"4;
%"SCONN288_ADR50017P087CC"
"3","(4575,2575)","0","pure_quanta","I175";
;
PART_NUMBER"DFHST8FS460"
MATERIAL"IO"
PART_TYPE"SMLF"
VALUE"SCONN288_ADR50017-P087CC"
$LOCATION"J8"
NEEDS_NO_SIZE"TRUE"
CDS_LMAN_SYM_OUTLINE"-450,1775,450,-1775"
CDS_LIB"pure_quanta"
CDS_LOCATION"J8"
$SEC"3"
CDS_SEC"3";
"G3"
$PN"G3"9;
"G2"
$PN"G2"9;
"G1"
$PN"G1"9;
"VSS62"
$PN"141"9;
"VSS61"
$PN"139"9;
"VSS60"
$PN"136"9;
"VSS58"
$PN"132"9;
"VSS104"
$PN"240"8;
"VSS102"
$PN"235"8;
"VSS100"
$PN"230"8;
"VIN_BULK2"
$PN"146"4;
"VIN_BULK1"
$PN"145"4;
"VIN_BULK0"
$PN"1"4;
"VSS126"
$PN"288"8;
"VSS125"
$PN"286"8;
"VSS124"
$PN"284"8;
"VSS123"
$PN"281"8;
"VSS122"
$PN"279"8;
"VSS121"
$PN"277"8;
"VSS120"
$PN"275"8;
"VSS119"
$PN"273"8;
"VSS118"
$PN"270"8;
"VSS117"
$PN"268"8;
"VSS116"
$PN"266"8;
"VSS115"
$PN"264"8;
"VSS114"
$PN"262"8;
"VSS113"
$PN"259"8;
"VSS112"
$PN"257"8;
"VSS111"
$PN"255"8;
"VSS110"
$PN"253"8;
"VSS109"
$PN"251"8;
"VSS108"
$PN"248"8;
"VSS107"
$PN"246"8;
"VSS106"
$PN"244"8;
"VSS105"
$PN"242"8;
"VSS103"
$PN"237"8;
"VSS101"
$PN"233"8;
"VSS99"
$PN"228"8;
"VSS98"
$PN"226"8;
"VSS97"
$PN"224"8;
"VSS96"
$PN"222"8;
"VSS95"
$PN"219"8;
"VSS94"
$PN"216"8;
"VSS93"
$PN"214"8;
"VSS92"
$PN"212"8;
"VSS91"
$PN"210"8;
"VSS90"
$PN"208"8;
"VSS89"
$PN"206"8;
"VSS88"
$PN"204"8;
"VSS87"
$PN"202"8;
"VSS86"
$PN"199"8;
"VSS85"
$PN"197"8;
"VSS84"
$PN"195"8;
"VSS83"
$PN"193"8;
"VSS82"
$PN"191"8;
"VSS81"
$PN"188"8;
"VSS80"
$PN"186"8;
"VSS79"
$PN"184"8;
"VSS78"
$PN"182"8;
"VSS77"
$PN"180"8;
"VSS76"
$PN"177"8;
"VSS75"
$PN"175"8;
"VSS74"
$PN"173"8;
"VSS73"
$PN"171"8;
"VSS72"
$PN"169"8;
"VSS71"
$PN"166"8;
"VSS70"
$PN"164"8;
"VSS69"
$PN"162"8;
"VSS68"
$PN"160"8;
"VSS67"
$PN"158"8;
"VSS66"
$PN"155"8;
"VSS65"
$PN"153"8;
"VSS64"
$PN"151"8;
"VSS63"
$PN"143"9;
"VSS59"
$PN"134"9;
"VSS57"
$PN"130"9;
"VSS56"
$PN"128"9;
"VSS55"
$PN"125"9;
"VSS54"
$PN"123"9;
"VSS53"
$PN"121"9;
"VSS52"
$PN"119"9;
"VSS51"
$PN"117"9;
"VSS50"
$PN"114"9;
"VSS49"
$PN"112"9;
"VSS48"
$PN"110"9;
"VSS47"
$PN"108"9;
"VSS46"
$PN"106"9;
"VSS45"
$PN"103"9;
"VSS44"
$PN"101"9;
"VSS43"
$PN"99"9;
"VSS42"
$PN"97"9;
"VSS41"
$PN"95"9;
"VSS40"
$PN"92"9;
"VSS39"
$PN"90"9;
"VSS38"
$PN"88"9;
"VSS37"
$PN"85"9;
"VSS36"
$PN"83"9;
"VSS35"
$PN"81"9;
"VSS34"
$PN"79"9;
"VSS33"
$PN"77"9;
"VSS32"
$PN"75"9;
"VSS31"
$PN"73"9;
"VSS30"
$PN"71"9;
"VSS29"
$PN"69"9;
"VSS28"
$PN"67"9;
"VSS27"
$PN"65"9;
"VSS26"
$PN"63"9;
"VSS25"
$PN"61"9;
"VSS24"
$PN"59"9;
"VSS23"
$PN"57"9;
"VSS22"
$PN"54"9;
"VSS21"
$PN"52"9;
"VSS20"
$PN"50"9;
"VSS19"
$PN"48"9;
"VSS18"
$PN"46"9;
"VSS17"
$PN"43"9;
"VSS16"
$PN"41"9;
"VSS15"
$PN"39"9;
"VSS14"
$PN"37"9;
"VSS13"
$PN"35"9;
"VSS12"
$PN"32"9;
"VSS11"
$PN"30"9;
"VSS10"
$PN"28"9;
"VSS9"
$PN"26"9;
"VSS8"
$PN"24"9;
"VSS7"
$PN"21"9;
"VSS6"
$PN"19"9;
"VSS5"
$PN"17"9;
"VSS4"
$PN"15"9;
"VSS3"
$PN"13"9;
"VSS2"
$PN"10"9;
"VSS1"
$PN"8"9;
"VSS0"
$PN"6"9;
%"UNIVERSAL_GND"
"1","(5425,500)","0","logical_power","I176";
;
CDS_LIB"logical_power"
HDL_POWER"GND";
"A"9;
%"SCONN288_ADR50017P087CC"
"2","(1150,3200)","0","pure_quanta","I178";
;
PART_NUMBER"DFHST8FS460"
MATERIAL"IO"
VALUE"SCONN288_ADR50017-P087CC"
PART_TYPE"SMLF"
LOCATION"J8"
NEEDS_NO_SIZE"TRUE"
CDS_LMAN_SYM_OUTLINE"-600,1150,600,-1150"
CDS_LIB"pure_quanta"
$SEC"2"
CDS_SEC"2";
"DQS7_A_C||TDQS7_A_C \B"
$PN"178"34;
"DQS6_A_T||TDQS6_A_T"
$PN"168"69;
"DQS8_B_T||TDQS8_B_T"
$PN"283"61;
"DQS8_B_C||TDQS8_B_C \B"
$PN"282"42;
"DQS7_B_T||TDQS7_B_T"
$PN"272"60;
"DQS0_A_C \B"
$PN"12"40;
"DQS0_A_T"
$PN"11"63;
"DQS0_B_C \B"
$PN"105"49;
"DQS0_B_T"
$PN"104"53;
"DQS1_A_C \B"
$PN"23"38;
"DQS1_A_T"
$PN"22"64;
"DQS1_B_C \B"
$PN"116"50;
"DQS1_B_T"
$PN"115"54;
"DQS2_A_C \B"
$PN"34"39;
"DQS2_A_T"
$PN"33"65;
"DQS2_B_C \B"
$PN"127"48;
"DQS2_B_T"
$PN"126"55;
"DQS3_A_C \B"
$PN"45"37;
"DQS3_A_T"
$PN"44"66;
"DQS3_B_C \B"
$PN"138"47;
"DQS3_B_T"
$PN"137"56;
"DQS4_A_C \B"
$PN"56"36;
"DQS4_A_T"
$PN"55"67;
"DQS4_B_C \B"
$PN"238"46;
"DQS4_B_T"
$PN"239"57;
"DQS5_A_C||TDQS5_A_C||DQS5_A_T||TDQS5_A_T \B"
$PN"156"35;
"DQS5_A_T||TDQS5_A_T"
$PN"157"68;
"DQS5_B_C||TDQS5_B_C \B"
$PN"249"45;
"DQS5_B_T||TDQS5_B_T"
$PN"250"58;
"DQS6_A_C||TDQS6_A_C||DQS6_A_T||TDQS6_A_T \B"
$PN"167"33;
"DQS6_B_C||TDQS6_B_C \B"
$PN"260"44;
"DQS6_B_T||TDQS6_B_T"
$PN"261"59;
"DQS7_A_T||TDQS7_A_T"
$PN"179"70;
"DQS7_B_C||TDQS7_B_C \B"
$PN"271"43;
"DQS8_A_C||TDQS8_A_C \B"
$PN"189"32;
"DQS8_A_T||TDQS8_A_T"
$PN"190"52;
"DQS9_A_C||TDQS9_A_C \B"
$PN"200"31;
"DQS9_A_T||TDQS9_A_T"
$PN"201"51;
"DQS9_B_C||TDQS9_B_C \B"
$PN"94"41;
"DQS9_B_T||TDQS9_B_T||DBI4_B_N"
$PN"93"62;
%"Q_RES"
"1","(-3400,1525)","0","pure_quanta","I180";
;
PART_NUMBER"CS04992FB07"
VALUE"49.9"
MATERIAL"CHIP"
$LOCATION"R3882"
CDS_LIB"pure_quanta"
PACK_TYPE"0402LF"
TOLERANCE"1%"
WATTAGE"1/16W"
CDS_LOCATION"R3882"
$SEC"1"
CDS_SEC"1";
"B"
$PN"2"25;
"A"
$PN"1"24;
%"Q_RES"
"2","(-2125,50)","0","pure_quanta","I2";
;
PART_NUMBER"CS41962FB03"
WATTAGE"1/16W"
TOLERANCE"1%"
MATERIAL"CHIP"
PACK_TYPE"0402LF"
VALUE"196K"
$LOCATION"R33"
CDS_LIB"pure_quanta"
CDS_LOCATION"R33"
$SEC"1"
CDS_SEC"1";
"A"
$PN"1"72;
"B"
$PN"2"5;
%"TAP"
"1","(-2350,2050)","2","standard","I24";
;
CDS_LIB"standard"
BODY_TYPE"PLUMBING"
HDL_TAP"TRUE";
"B \NAC \NWC"10;
"S \NAC"
BN"1"95;
%"TAP"
"1","(-2350,2100)","2","standard","I25";
;
CDS_LIB"standard"
BODY_TYPE"PLUMBING"
HDL_TAP"TRUE";
"B \NAC \NWC"10;
"S \NAC"
BN"2"29;
%"TAP"
"1","(-2350,2150)","2","standard","I26";
;
CDS_LIB"standard"
BODY_TYPE"PLUMBING"
HDL_TAP"TRUE";
"B \NAC \NWC"10;
"S \NAC"
BN"3"178;
%"TAP"
"1","(-2350,2200)","2","standard","I27";
;
CDS_LIB"standard"
BODY_TYPE"PLUMBING"
HDL_TAP"TRUE";
"B \NAC \NWC"10;
"S \NAC"
BN"4"94;
%"TAP"
"1","(-2350,2250)","2","standard","I28";
;
CDS_LIB"standard"
BODY_TYPE"PLUMBING"
HDL_TAP"TRUE";
"B \NAC \NWC"10;
"S \NAC"
BN"5"93;
%"TAP"
"1","(-2350,2300)","2","standard","I29";
;
CDS_LIB"standard"
BODY_TYPE"PLUMBING"
HDL_TAP"TRUE";
"B \NAC \NWC"10;
"S \NAC"
BN"6"92;
%"TAP"
"1","(-2350,2350)","2","standard","I30";
;
CDS_LIB"standard"
BODY_TYPE"PLUMBING"
HDL_TAP"TRUE";
"B \NAC \NWC"10;
"S \NAC"
BN"7"77;
%"TAP"
"1","(-2350,2450)","2","standard","I31";
;
CDS_LIB"standard"
BODY_TYPE"PLUMBING"
HDL_TAP"TRUE";
"B \NAC \NWC"11;
"S \NAC"
BN"0"30;
%"TAP"
"1","(-2350,2500)","2","standard","I32";
;
CDS_LIB"standard"
BODY_TYPE"PLUMBING"
HDL_TAP"TRUE";
"B \NAC \NWC"11;
"S \NAC"
BN"1"76;
%"TAP"
"1","(-2350,2550)","2","standard","I33";
;
CDS_LIB"standard"
BODY_TYPE"PLUMBING"
HDL_TAP"TRUE";
"B \NAC \NWC"11;
"S \NAC"
BN"2"91;
%"TAP"
"1","(-2350,2600)","2","standard","I34";
;
CDS_LIB"standard"
BODY_TYPE"PLUMBING"
HDL_TAP"TRUE";
"B \NAC \NWC"11;
"S \NAC"
BN"3"90;
%"TAP"
"1","(-2350,2650)","2","standard","I35";
;
CDS_LIB"standard"
BODY_TYPE"PLUMBING"
HDL_TAP"TRUE";
"B \NAC \NWC"11;
"S \NAC"
BN"4"75;
%"TAP"
"1","(-2350,2700)","2","standard","I36";
;
CDS_LIB"standard"
BODY_TYPE"PLUMBING"
HDL_TAP"TRUE";
"B \NAC \NWC"11;
"S \NAC"
BN"5"177;
%"TAP"
"1","(-2350,2750)","2","standard","I37";
;
CDS_LIB"standard"
BODY_TYPE"PLUMBING"
HDL_TAP"TRUE";
"B \NAC \NWC"11;
"S \NAC"
BN"6"89;
%"TAP"
"1","(-2350,2800)","2","standard","I38";
;
CDS_LIB"standard"
BODY_TYPE"PLUMBING"
HDL_TAP"TRUE";
"B \NAC \NWC"11;
"S \NAC"
BN"7"74;
%"TAP"
"1","(-2350,3500)","2","standard","I39";
;
CDS_LIB"standard"
BODY_TYPE"PLUMBING"
HDL_TAP"TRUE";
"B \NAC \NWC"15;
"S \NAC"
BN"0"79;
%"TAP"
"1","(-2350,3550)","2","standard","I40";
;
CDS_LIB"standard"
BODY_TYPE"PLUMBING"
HDL_TAP"TRUE";
"B \NAC \NWC"15;
"S \NAC"
BN"1"81;
%"TAP"
"1","(-2350,3600)","2","standard","I41";
;
CDS_LIB"standard"
BODY_TYPE"PLUMBING"
HDL_TAP"TRUE";
"B \NAC \NWC"15;
"S \NAC"
BN"2"83;
%"TAP"
"1","(-2350,3650)","2","standard","I42";
;
CDS_LIB"standard"
BODY_TYPE"PLUMBING"
HDL_TAP"TRUE";
"B \NAC \NWC"15;
"S \NAC"
BN"3"85;
%"TAP"
"1","(-2350,3700)","2","standard","I43";
;
CDS_LIB"standard"
BODY_TYPE"PLUMBING"
HDL_TAP"TRUE";
"B \NAC \NWC"15;
"S \NAC"
BN"4"86;
%"TAP"
"1","(-2350,3800)","2","standard","I44";
;
CDS_LIB"standard"
BODY_TYPE"PLUMBING"
HDL_TAP"TRUE";
"B \NAC \NWC"15;
"S \NAC"
BN"6"88;
%"TAP"
"1","(-2350,3750)","2","standard","I45";
;
CDS_LIB"standard"
BODY_TYPE"PLUMBING"
HDL_TAP"TRUE";
"B \NAC \NWC"15;
"S \NAC"
BN"5"87;
%"TAP"
"1","(-2350,3900)","2","standard","I46";
;
CDS_LIB"standard"
BODY_TYPE"PLUMBING"
HDL_TAP"TRUE";
"B \NAC \NWC"12;
"S \NAC"
BN"0"78;
%"TAP"
"1","(-2350,3950)","2","standard","I47";
;
CDS_LIB"standard"
BODY_TYPE"PLUMBING"
HDL_TAP"TRUE";
"B \NAC \NWC"12;
"S \NAC"
BN"1"80;
%"TAP"
"1","(-2350,4050)","2","standard","I48";
;
CDS_LIB"standard"
BODY_TYPE"PLUMBING"
HDL_TAP"TRUE";
"B \NAC \NWC"12;
"S \NAC"
BN"3"84;
%"TAP"
"1","(-2350,4000)","2","standard","I49";
;
CDS_LIB"standard"
BODY_TYPE"PLUMBING"
HDL_TAP"TRUE";
"B \NAC \NWC"12;
"S \NAC"
BN"2"82;
%"SCONN288_ADR50017P087CC"
"1","(-1525,2475)","0","pure_quanta","I50";
;
PART_NUMBER"DFHST8FS460"
MATERIAL"IO"
PART_TYPE"SMLF"
VALUE"SCONN288_ADR50017-P087CC"
$LOCATION"J8"
NEEDS_NO_SIZE"TRUE"
CDS_LMAN_SYM_OUTLINE"-450,1875,450,-1875"
CDS_LIB"pure_quanta"
CDS_LOCATION"J8"
$SEC"1"
CDS_SEC"1";
"DQ31_A"
$PN"194"73;
"CB7_A"
$PN"205"74;
"CB4_A"
$PN"58"75;
"CB1_A"
$PN"53"76;
"CB7_B"
$PN"236"77;
"ALERT_N \B"
$PN"62"23;
"CA0_A"
$PN"66"78;
"CA0_B"
$PN"76"79;
"CA1_A"
$PN"211"80;
"CA1_B"
$PN"221"81;
"CA2_A"
$PN"68"82;
"CA2_B"
$PN"78"83;
"CA3_A"
$PN"213"84;
"CA3_B"
$PN"223"85;
"CA4_A"
$PN"70"174;
"CA4_B"
$PN"80"86;
"CA5_A"
$PN"215"175;
"CA5_B"
$PN"225"87;
"CA6_A"
$PN"72"176;
"CA6_B"
$PN"82"88;
"CB6_A"
$PN"203"89;
"CB5_A"
$PN"60"177;
"CB3_A"
$PN"198"90;
"CB2_A"
$PN"196"91;
"CB0_A"
$PN"51"30;
"CB6_B"
$PN"234"92;
"CB5_B"
$PN"91"93;
"CB4_B"
$PN"89"94;
"CB3_B"
$PN"243"178;
"CB2_B"
$PN"241"29;
"CB1_B"
$PN"98"95;
"CB0_B"
$PN"96"28;
"CK_C \B"
$PN"218"96;
"CK_T"
$PN"217"97;
"CS0_A_N"
$PN"64"98;
"CS0_B_N"
$PN"84"99;
"CS1_A_N"
$PN"209"100;
"CS1_B_N"
$PN"229"101;
"DQ30_A"
$PN"192"102;
"DQ29_A"
$PN"49"103;
"DQ28_A"
$PN"47"104;
"DQ27_A"
$PN"187"105;
"DQ26_A"
$PN"185"106;
"DQ25_A"
$PN"42"107;
"DQ24_A"
$PN"40"108;
"DQ23_A"
$PN"183"109;
"DQ22_A"
$PN"181"110;
"DQ21_A"
$PN"38"111;
"DQ20_A"
$PN"36"112;
"DQ19_A"
$PN"176"113;
"DQ18_A"
$PN"174"114;
"DQ17_A"
$PN"31"115;
"DQ16_A"
$PN"29"171;
"DQ15_A"
$PN"172"173;
"DQ14_A"
$PN"170"172;
"DQ13_A"
$PN"27"116;
"DQ12_A"
$PN"25"117;
"DQ11_A"
$PN"165"118;
"DQ10_A"
$PN"163"119;
"DQ9_A"
$PN"20"120;
"DQ8_A"
$PN"18"121;
"DQ7_A"
$PN"161"122;
"DQ6_A"
$PN"159"123;
"DQ5_A"
$PN"16"124;
"DQ4_A"
$PN"14"125;
"DQ3_A"
$PN"154"126;
"DQ2_A"
$PN"152"127;
"DQ1_A"
$PN"9"128;
"DQ0_A"
$PN"7"129;
"DQ31_B"
$PN"287"130;
"DQ30_B"
$PN"285"131;
"DQ29_B"
$PN"142"132;
"DQ28_B"
$PN"140"133;
"DQ27_B"
$PN"280"134;
"DQ26_B"
$PN"278"135;
"DQ25_B"
$PN"135"136;
"DQ24_B"
$PN"133"137;
"DQ23_B"
$PN"276"138;
"DQ22_B"
$PN"274"139;
"DQ21_B"
$PN"131"140;
"DQ20_B"
$PN"129"141;
"DQ19_B"
$PN"269"142;
"DQ18_B"
$PN"267"143;
"DQ17_B"
$PN"124"144;
"DQ16_B"
$PN"122"145;
"DQ15_B"
$PN"265"146;
"DQ14_B"
$PN"263"147;
"DQ13_B"
$PN"120"148;
"DQ12_B"
$PN"118"170;
"DQ11_B"
$PN"258"149;
"DQ10_B"
$PN"256"150;
"DQ9_B"
$PN"113"151;
"DQ8_B"
$PN"111"152;
"DQ7_B"
$PN"254"153;
"DQ6_B"
$PN"252"154;
"DQ5_B"
$PN"109"155;
"DQ4_B"
$PN"107"156;
"DQ3_B"
$PN"247"157;
"DQ2_B"
$PN"245"158;
"DQ1_B"
$PN"102"159;
"DQ0_B"
$PN"100"160;
"HSA"
$PN"148"21;
"HSCL"
$PN"4"24;
"HSDA"
$PN"5"20;
"LBD||RSP_A_N"
$PN"86"161;
"LBS||RSP_B_N"
$PN"87"162;
"PAR_A"
$PN"74"163;
"PAR_B"
$PN"227"164;
"PWR_GOOD||FAIL_N"
$PN"147"26;
"RESET_N \B"
$PN"207"22;
"RFU6"
$PN"232"27;
"RFU5"
$PN"231"71;
"RFU4"
$PN"220"165;
"RFU3"
$PN"150"166;
"RFU2"
$PN"149"167;
"RFU1"
$PN"144"168;
"RFU0"
$PN"2"169;
"VIN_MGMT"
$PN"3"1;
%"TAP"
"1","(-700,1000)","0","standard","I51";
;
CDS_LIB"standard"
BODY_TYPE"PLUMBING"
HDL_TAP"TRUE";
"B \NAC \NWC"14;
"S \NAC"
BN"0"160;
%"TAP"
"1","(-700,1050)","0","standard","I52";
;
CDS_LIB"standard"
BODY_TYPE"PLUMBING"
HDL_TAP"TRUE";
"B \NAC \NWC"14;
"S \NAC"
BN"1"159;
%"TAP"
"1","(-700,1150)","0","standard","I53";
;
CDS_LIB"standard"
BODY_TYPE"PLUMBING"
HDL_TAP"TRUE";
"B \NAC \NWC"14;
"S \NAC"
BN"3"157;
%"TAP"
"1","(-700,1100)","0","standard","I54";
;
CDS_LIB"standard"
BODY_TYPE"PLUMBING"
HDL_TAP"TRUE";
"B \NAC \NWC"14;
"S \NAC"
BN"2"158;
%"TAP"
"1","(-700,1200)","0","standard","I55";
;
CDS_LIB"standard"
BODY_TYPE"PLUMBING"
HDL_TAP"TRUE";
"B \NAC \NWC"14;
"S \NAC"
BN"4"156;
%"TAP"
"1","(-700,1250)","0","standard","I56";
;
CDS_LIB"standard"
BODY_TYPE"PLUMBING"
HDL_TAP"TRUE";
"B \NAC \NWC"14;
"S \NAC"
BN"5"155;
%"TAP"
"1","(-700,1300)","0","standard","I57";
;
CDS_LIB"standard"
BODY_TYPE"PLUMBING"
HDL_TAP"TRUE";
"B \NAC \NWC"14;
"S \NAC"
BN"6"154;
%"TAP"
"1","(-700,1400)","0","standard","I58";
;
CDS_LIB"standard"
BODY_TYPE"PLUMBING"
HDL_TAP"TRUE";
"B \NAC \NWC"14;
"S \NAC"
BN"8"152;
%"TAP"
"1","(-700,1350)","0","standard","I59";
;
CDS_LIB"standard"
BODY_TYPE"PLUMBING"
HDL_TAP"TRUE";
"B \NAC \NWC"14;
"S \NAC"
BN"7"153;
%"TAP"
"1","(-700,1450)","0","standard","I60";
;
CDS_LIB"standard"
BODY_TYPE"PLUMBING"
HDL_TAP"TRUE";
"B \NAC \NWC"14;
"S \NAC"
BN"9"151;
%"TAP"
"1","(-700,1500)","0","standard","I61";
;
CDS_LIB"standard"
BODY_TYPE"PLUMBING"
HDL_TAP"TRUE";
"B \NAC \NWC"14;
"S \NAC"
BN"10"150;
%"TAP"
"1","(-700,1550)","0","standard","I62";
;
CDS_LIB"standard"
BODY_TYPE"PLUMBING"
HDL_TAP"TRUE";
"B \NAC \NWC"14;
"S \NAC"
BN"11"149;
%"TAP"
"1","(-700,1600)","0","standard","I63";
;
CDS_LIB"standard"
BODY_TYPE"PLUMBING"
HDL_TAP"TRUE";
"B \NAC \NWC"14;
"S \NAC"
BN"12"170;
%"TAP"
"1","(-700,1650)","0","standard","I64";
;
CDS_LIB"standard"
BODY_TYPE"PLUMBING"
HDL_TAP"TRUE";
"B \NAC \NWC"14;
"S \NAC"
BN"13"148;
%"TAP"
"1","(-700,1700)","0","standard","I65";
;
CDS_LIB"standard"
BODY_TYPE"PLUMBING"
HDL_TAP"TRUE";
"B \NAC \NWC"14;
"S \NAC"
BN"14"147;
%"TAP"
"1","(-700,1750)","0","standard","I66";
;
CDS_LIB"standard"
BODY_TYPE"PLUMBING"
HDL_TAP"TRUE";
"B \NAC \NWC"14;
"S \NAC"
BN"15"146;
%"TAP"
"1","(-700,1850)","0","standard","I67";
;
CDS_LIB"standard"
BODY_TYPE"PLUMBING"
HDL_TAP"TRUE";
"B \NAC \NWC"14;
"S \NAC"
BN"17"144;
%"TAP"
"1","(-700,1800)","0","standard","I68";
;
CDS_LIB"standard"
BODY_TYPE"PLUMBING"
HDL_TAP"TRUE";
"B \NAC \NWC"14;
"S \NAC"
BN"16"145;
%"TAP"
"1","(-700,1900)","0","standard","I69";
;
CDS_LIB"standard"
BODY_TYPE"PLUMBING"
HDL_TAP"TRUE";
"B \NAC \NWC"14;
"S \NAC"
BN"18"143;
%"TAP"
"1","(-700,1950)","0","standard","I70";
;
CDS_LIB"standard"
BODY_TYPE"PLUMBING"
HDL_TAP"TRUE";
"B \NAC \NWC"14;
"S \NAC"
BN"19"142;
%"TAP"
"1","(-700,2000)","0","standard","I71";
;
CDS_LIB"standard"
BODY_TYPE"PLUMBING"
HDL_TAP"TRUE";
"B \NAC \NWC"14;
"S \NAC"
BN"20"141;
%"TAP"
"1","(-700,2050)","0","standard","I72";
;
CDS_LIB"standard"
BODY_TYPE"PLUMBING"
HDL_TAP"TRUE";
"B \NAC \NWC"14;
"S \NAC"
BN"21"140;
%"TAP"
"1","(-700,2100)","0","standard","I73";
;
CDS_LIB"standard"
BODY_TYPE"PLUMBING"
HDL_TAP"TRUE";
"B \NAC \NWC"14;
"S \NAC"
BN"22"139;
%"TAP"
"1","(-700,2150)","0","standard","I74";
;
CDS_LIB"standard"
BODY_TYPE"PLUMBING"
HDL_TAP"TRUE";
"B \NAC \NWC"14;
"S \NAC"
BN"23"138;
%"TAP"
"1","(-700,2200)","0","standard","I75";
;
CDS_LIB"standard"
BODY_TYPE"PLUMBING"
HDL_TAP"TRUE";
"B \NAC \NWC"14;
"S \NAC"
BN"24"137;
%"TAP"
"1","(-700,2300)","0","standard","I76";
;
CDS_LIB"standard"
BODY_TYPE"PLUMBING"
HDL_TAP"TRUE";
"B \NAC \NWC"14;
"S \NAC"
BN"26"135;
%"TAP"
"1","(-700,2250)","0","standard","I77";
;
CDS_LIB"standard"
BODY_TYPE"PLUMBING"
HDL_TAP"TRUE";
"B \NAC \NWC"14;
"S \NAC"
BN"25"136;
%"TAP"
"1","(-700,2350)","0","standard","I78";
;
CDS_LIB"standard"
BODY_TYPE"PLUMBING"
HDL_TAP"TRUE";
"B \NAC \NWC"14;
"S \NAC"
BN"27"134;
%"TAP"
"1","(-700,2400)","0","standard","I79";
;
CDS_LIB"standard"
BODY_TYPE"PLUMBING"
HDL_TAP"TRUE";
"B \NAC \NWC"14;
"S \NAC"
BN"28"133;
%"TAP"
"1","(-700,2450)","0","standard","I80";
;
CDS_LIB"standard"
BODY_TYPE"PLUMBING"
HDL_TAP"TRUE";
"B \NAC \NWC"14;
"S \NAC"
BN"29"132;
%"TAP"
"1","(-700,2550)","0","standard","I81";
;
CDS_LIB"standard"
BODY_TYPE"PLUMBING"
HDL_TAP"TRUE";
"B \NAC \NWC"14;
"S \NAC"
BN"31"130;
%"TAP"
"1","(-700,2500)","0","standard","I82";
;
CDS_LIB"standard"
BODY_TYPE"PLUMBING"
HDL_TAP"TRUE";
"B \NAC \NWC"14;
"S \NAC"
BN"30"131;
%"TAP"
"1","(-700,2650)","0","standard","I83";
;
CDS_LIB"standard"
BODY_TYPE"PLUMBING"
HDL_TAP"TRUE";
"B \NAC \NWC"13;
"S \NAC"
BN"0"129;
%"TAP"
"1","(-700,2750)","0","standard","I84";
;
CDS_LIB"standard"
BODY_TYPE"PLUMBING"
HDL_TAP"TRUE";
"B \NAC \NWC"13;
"S \NAC"
BN"2"127;
%"TAP"
"1","(-700,2700)","0","standard","I85";
;
CDS_LIB"standard"
BODY_TYPE"PLUMBING"
HDL_TAP"TRUE";
"B \NAC \NWC"13;
"S \NAC"
BN"1"128;
%"TAP"
"1","(-700,2800)","0","standard","I86";
;
CDS_LIB"standard"
BODY_TYPE"PLUMBING"
HDL_TAP"TRUE";
"B \NAC \NWC"13;
"S \NAC"
BN"3"126;
%"TAP"
"1","(-700,2850)","0","standard","I87";
;
CDS_LIB"standard"
BODY_TYPE"PLUMBING"
HDL_TAP"TRUE";
"B \NAC \NWC"13;
"S \NAC"
BN"4"125;
%"TAP"
"1","(-700,2900)","0","standard","I88";
;
CDS_LIB"standard"
BODY_TYPE"PLUMBING"
HDL_TAP"TRUE";
"B \NAC \NWC"13;
"S \NAC"
BN"5"124;
%"TAP"
"1","(-700,3000)","0","standard","I89";
;
CDS_LIB"standard"
BODY_TYPE"PLUMBING"
HDL_TAP"TRUE";
"B \NAC \NWC"13;
"S \NAC"
BN"7"122;
%"TAP"
"1","(-700,2950)","0","standard","I90";
;
CDS_LIB"standard"
BODY_TYPE"PLUMBING"
HDL_TAP"TRUE";
"B \NAC \NWC"13;
"S \NAC"
BN"6"123;
%"TAP"
"1","(-700,3050)","0","standard","I91";
;
CDS_LIB"standard"
BODY_TYPE"PLUMBING"
HDL_TAP"TRUE";
"B \NAC \NWC"13;
"S \NAC"
BN"8"121;
%"TAP"
"1","(-700,3100)","0","standard","I92";
;
CDS_LIB"standard"
BODY_TYPE"PLUMBING"
HDL_TAP"TRUE";
"B \NAC \NWC"13;
"S \NAC"
BN"9"120;
%"TAP"
"1","(-700,3150)","0","standard","I93";
;
CDS_LIB"standard"
BODY_TYPE"PLUMBING"
HDL_TAP"TRUE";
"B \NAC \NWC"13;
"S \NAC"
BN"10"119;
%"TAP"
"1","(-700,3200)","0","standard","I94";
;
CDS_LIB"standard"
BODY_TYPE"PLUMBING"
HDL_TAP"TRUE";
"B \NAC \NWC"13;
"S \NAC"
BN"11"118;
%"TAP"
"1","(-700,3250)","0","standard","I95";
;
CDS_LIB"standard"
BODY_TYPE"PLUMBING"
HDL_TAP"TRUE";
"B \NAC \NWC"13;
"S \NAC"
BN"12"117;
%"TAP"
"1","(-700,3300)","0","standard","I96";
;
CDS_LIB"standard"
BODY_TYPE"PLUMBING"
HDL_TAP"TRUE";
"B \NAC \NWC"13;
"S \NAC"
BN"13"116;
%"TAP"
"1","(-700,3350)","0","standard","I97";
;
CDS_LIB"standard"
BODY_TYPE"PLUMBING"
HDL_TAP"TRUE";
"B \NAC \NWC"13;
"S \NAC"
BN"14"172;
%"TAP"
"1","(-700,3450)","0","standard","I98";
;
CDS_LIB"standard"
BODY_TYPE"PLUMBING"
HDL_TAP"TRUE";
"B \NAC \NWC"13;
"S \NAC"
BN"16"171;
%"TAP"
"1","(-700,3400)","0","standard","I99";
;
CDS_LIB"standard"
BODY_TYPE"PLUMBING"
HDL_TAP"TRUE";
"B \NAC \NWC"13;
"S \NAC"
BN"15"173;
END.
